(kicad_pcb
	(version 20260206)
	(generator "pcbnew")
	(generator_version "10.0")
	(general
		(thickness 1.6)
		(legacy_teardrops no)
	)
	(paper "A4")
	(title_block
		(title "01162023_DA0F0TEBIF0_F0T_Expander_BD_F_brd_V02_OCP.brd")
		(comment 1 "Grand Teton / footprints 8347-8354 of 9728")
	)
	(layers
		(0 "F.Cu" signal "TOP")
		(4 "In1.Cu" signal "GND")
		(6 "In2.Cu" signal "VCC")
		(8 "In3.Cu" signal "VCC1")
		(10 "In4.Cu" signal "GND1")
		(12 "In5.Cu" signal "IN1")
		(14 "In6.Cu" signal "GND2")
		(16 "In7.Cu" signal "IN2")
		(18 "In8.Cu" signal "GND3")
		(20 "In9.Cu" signal "IN3")
		(22 "In10.Cu" signal "GND4")
		(24 "In11.Cu" signal "IN4")
		(26 "In12.Cu" signal "GND5")
		(28 "In13.Cu" signal "IN5")
		(30 "In14.Cu" signal "GND6")
		(32 "In15.Cu" signal "IN6")
		(34 "In16.Cu" signal "GND7")
		(2 "B.Cu" signal "BOTTOM")
		(9 "F.Adhes" user "F.Adhesive")
		(11 "B.Adhes" user "B.Adhesive")
		(13 "F.Paste" user "Package Geometry/Pastemask Top")
		(15 "B.Paste" user "Package Geometry/Pastemask Bottom")
		(5 "F.SilkS" user "Ref Des/Silkscreen Top")
		(7 "B.SilkS" user "Ref Des/Silkscreen Bottom")
		(1 "F.Mask" user "Board Geometry/Soldermask Top")
		(3 "B.Mask" user "Board Geometry/Soldermask Bottom")
		(17 "Dwgs.User" user "User.Drawings")
		(19 "Cmts.User" user "User.Comments")
		(21 "Eco1.User" user "User.Eco1")
		(23 "Eco2.User" user "User.Eco2")
		(25 "Edge.Cuts" user "Board Geometry/Outline")
		(27 "Margin" user)
		(31 "F.CrtYd" user "Package Geometry/Place Bound Top")
		(29 "B.CrtYd" user "Package Geometry/Place Bound Bottom")
		(35 "F.Fab" user "Ref Des/Assembly Top")
		(33 "B.Fab" user "Ref Des/Assembly Bottom")
	)
	(footprint ""
		(layer "B.Cu")
		(at 111.166656 -87.089996)
		(property "Reference" "C2664"
			(at 0 0 0)
			(layer "B.SilkS")
			(hide yes)
			(effects
				(font
					(size 1.27 1.27)
				)
				(justify mirror)
			)
		)
		(property "Value" ""
			(at 0 0 0)
			(layer "B.Fab")
			(effects
				(font
					(size 1.27 1.27)
				)
				(justify mirror)
			)
		)
		(duplicate_pad_numbers_are_jumpers no)
		(fp_line
			(start -0.7874 -0.4064)
			(end -0.7874 0.4064)
			(stroke
				(width 0.1524)
				(type default)
			)
			(layer "B.SilkS")
		)
		(fp_line
			(start -0.7874 0.4064)
			(end 0.7874 0.4064)
			(stroke
				(width 0.1524)
				(type default)
			)
			(layer "B.SilkS")
		)
		(fp_line
			(start 0.7874 -0.4064)
			(end -0.7874 -0.4064)
			(stroke
				(width 0.1524)
				(type default)
			)
			(layer "B.SilkS")
		)
		(fp_line
			(start 0.7874 0.4064)
			(end 0.7874 -0.4064)
			(stroke
				(width 0.1524)
				(type default)
			)
			(layer "B.SilkS")
		)
		(fp_line
			(start -0.67945 -0.3048)
			(end -0.67945 0.3048)
			(stroke
				(width 0.1)
				(type default)
			)
			(layer "B.Fab")
		)
		(fp_line
			(start -0.67945 0.3048)
			(end -0.120396 0.3048)
			(stroke
				(width 0.1)
				(type default)
			)
			(layer "B.Fab")
		)
		(fp_line
			(start -0.12065 -0.3048)
			(end -0.67945 -0.3048)
			(stroke
				(width 0.1)
				(type default)
			)
			(layer "B.Fab")
		)
		(fp_line
			(start -0.12065 -0.2794)
			(end -0.12065 -0.3048)
			(stroke
				(width 0.1)
				(type default)
			)
			(layer "B.Fab")
		)
		(fp_line
			(start -0.120396 0.2794)
			(end 0.12065 0.2794)
			(stroke
				(width 0.1)
				(type default)
			)
			(layer "B.Fab")
		)
		(fp_line
			(start -0.120396 0.3048)
			(end -0.120396 0.2794)
			(stroke
				(width 0.1)
				(type default)
			)
			(layer "B.Fab")
		)
		(fp_line
			(start 0.12065 -0.305054)
			(end 0.12065 -0.2794)
			(stroke
				(width 0.1)
				(type default)
			)
			(layer "B.Fab")
		)
		(fp_line
			(start 0.12065 -0.2794)
			(end -0.12065 -0.2794)
			(stroke
				(width 0.1)
				(type default)
			)
			(layer "B.Fab")
		)
		(fp_line
			(start 0.12065 0.2794)
			(end 0.12065 0.3048)
			(stroke
				(width 0.1)
				(type default)
			)
			(layer "B.Fab")
		)
		(fp_line
			(start 0.12065 0.3048)
			(end 0.67945 0.3048)
			(stroke
				(width 0.1)
				(type default)
			)
			(layer "B.Fab")
		)
		(fp_line
			(start 0.67945 -0.305054)
			(end 0.12065 -0.305054)
			(stroke
				(width 0.1)
				(type default)
			)
			(layer "B.Fab")
		)
		(fp_line
			(start 0.67945 0.3048)
			(end 0.67945 -0.305054)
			(stroke
				(width 0.1)
				(type default)
			)
			(layer "B.Fab")
		)
		(pad "1" smd circle
			(at 0.40005 0 180)
			(size 0 0)
			(layers "B.Cu" "B.Mask" "B.Paste")
			(net "P3V3_VDD_9ZXL0851_0_7")
		)
		(pad "2" smd circle
			(at -0.40005 0 180)
			(size 0 0)
			(layers "B.Cu" "B.Mask" "B.Paste")
			(net "GND")
		)
	)
	(footprint ""
		(layer "B.Cu")
		(at 415.074862 -286.399732 90)
		(property "Reference" "C3506"
			(at 0 0 90)
			(layer "B.SilkS")
			(hide yes)
			(effects
				(font
					(size 1.27 1.27)
				)
				(justify mirror)
			)
		)
		(property "Value" ""
			(at 0 0 90)
			(layer "B.Fab")
			(effects
				(font
					(size 1.27 1.27)
				)
				(justify mirror)
			)
		)
		(duplicate_pad_numbers_are_jumpers no)
		(fp_line
			(start 0.299974 -0.150114)
			(end -0.299974 -0.150114)
			(stroke
				(width 0.1)
				(type default)
			)
			(layer "B.Fab")
		)
		(fp_line
			(start -0.299974 -0.150114)
			(end -0.299974 0.150114)
			(stroke
				(width 0.1)
				(type default)
			)
			(layer "B.Fab")
		)
		(fp_line
			(start 0.299974 0.150114)
			(end 0.299974 -0.150114)
			(stroke
				(width 0.1)
				(type default)
			)
			(layer "B.Fab")
		)
		(fp_line
			(start -0.299974 0.150114)
			(end 0.299974 0.150114)
			(stroke
				(width 0.1)
				(type default)
			)
			(layer "B.Fab")
		)
		(pad "1" smd rect
			(at 0.2667 0 270)
			(size 0.3048 0.381)
			(layers "B.Cu" "B.Mask" "B.Paste")
			(net "P1V25_SERDES_VDDPLL_PEX3")
		)
		(pad "2" smd rect
			(at -0.2667 0 270)
			(size 0.3048 0.381)
			(layers "B.Cu" "B.Mask" "B.Paste")
			(net "GND")
		)
	)
	(footprint ""
		(layer "B.Cu")
		(at 351.645982 -144.526 180)
		(property "Reference" "R4798"
			(at 0 0 0)
			(layer "B.SilkS")
			(hide yes)
			(effects
				(font
					(size 1.27 1.27)
				)
				(justify mirror)
			)
		)
		(property "Value" ""
			(at 0 0 0)
			(layer "B.Fab")
			(effects
				(font
					(size 1.27 1.27)
				)
				(justify mirror)
			)
		)
		(duplicate_pad_numbers_are_jumpers no)
		(fp_line
			(start 0.7874 0.4064)
			(end 0.7874 -0.4064)
			(stroke
				(width 0.1524)
				(type default)
			)
			(layer "B.SilkS")
		)
		(fp_line
			(start 0.7874 -0.4064)
			(end -0.7874 -0.4064)
			(stroke
				(width 0.1524)
				(type default)
			)
			(layer "B.SilkS")
		)
		(fp_line
			(start -0.7874 0.4064)
			(end 0.7874 0.4064)
			(stroke
				(width 0.1524)
				(type default)
			)
			(layer "B.SilkS")
		)
		(fp_line
			(start -0.7874 -0.4064)
			(end -0.7874 0.4064)
			(stroke
				(width 0.1524)
				(type default)
			)
			(layer "B.SilkS")
		)
		(fp_line
			(start 0.67945 0.3048)
			(end 0.67945 -0.305054)
			(stroke
				(width 0.1)
				(type default)
			)
			(layer "B.Fab")
		)
		(fp_line
			(start 0.67945 -0.305054)
			(end 0.12065 -0.305054)
			(stroke
				(width 0.1)
				(type default)
			)
			(layer "B.Fab")
		)
		(fp_line
			(start 0.12065 0.3048)
			(end 0.67945 0.3048)
			(stroke
				(width 0.1)
				(type default)
			)
			(layer "B.Fab")
		)
		(fp_line
			(start 0.12065 0.2794)
			(end 0.12065 0.3048)
			(stroke
				(width 0.1)
				(type default)
			)
			(layer "B.Fab")
		)
		(fp_line
			(start 0.12065 -0.2794)
			(end -0.12065 -0.2794)
			(stroke
				(width 0.1)
				(type default)
			)
			(layer "B.Fab")
		)
		(fp_line
			(start 0.12065 -0.305054)
			(end 0.12065 -0.2794)
			(stroke
				(width 0.1)
				(type default)
			)
			(layer "B.Fab")
		)
		(fp_line
			(start -0.120396 0.3048)
			(end -0.120396 0.2794)
			(stroke
				(width 0.1)
				(type default)
			)
			(layer "B.Fab")
		)
		(fp_line
			(start -0.120396 0.2794)
			(end 0.12065 0.2794)
			(stroke
				(width 0.1)
				(type default)
			)
			(layer "B.Fab")
		)
		(fp_line
			(start -0.12065 -0.2794)
			(end -0.12065 -0.3048)
			(stroke
				(width 0.1)
				(type default)
			)
			(layer "B.Fab")
		)
		(fp_line
			(start -0.12065 -0.3048)
			(end -0.67945 -0.3048)
			(stroke
				(width 0.1)
				(type default)
			)
			(layer "B.Fab")
		)
		(fp_line
			(start -0.67945 0.3048)
			(end -0.120396 0.3048)
			(stroke
				(width 0.1)
				(type default)
			)
			(layer "B.Fab")
		)
		(fp_line
			(start -0.67945 -0.3048)
			(end -0.67945 0.3048)
			(stroke
				(width 0.1)
				(type default)
			)
			(layer "B.Fab")
		)
		(pad "1" smd circle
			(at 0.40005 0)
			(size 0 0)
			(layers "B.Cu" "B.Mask" "B.Paste")
			(net "P3V3_AUX")
		)
		(pad "2" smd circle
			(at -0.40005 0)
			(size 0 0)
			(layers "B.Cu" "B.Mask" "B.Paste")
			(net "RST_PEX_NIC7_PERST_R_N")
		)
	)
	(footprint ""
		(layer "B.Cu")
		(at 344.645234 -326.945498 -90)
		(property "Reference" "C4312"
			(at 0 0 90)
			(layer "B.SilkS")
			(hide yes)
			(effects
				(font
					(size 1.27 1.27)
				)
				(justify mirror)
			)
		)
		(property "Value" ""
			(at 0 0 90)
			(layer "B.Fab")
			(effects
				(font
					(size 1.27 1.27)
				)
				(justify mirror)
			)
		)
		(duplicate_pad_numbers_are_jumpers no)
		(fp_line
			(start -1.2954 0.5842)
			(end 1.2954 0.5842)
			(stroke
				(width 0.1524)
				(type default)
			)
			(layer "B.SilkS")
		)
		(fp_line
			(start 1.2954 0.5842)
			(end 1.2954 -0.5842)
			(stroke
				(width 0.1524)
				(type default)
			)
			(layer "B.SilkS")
		)
		(fp_line
			(start -1.2954 -0.5842)
			(end -1.2954 0.5842)
			(stroke
				(width 0.1524)
				(type default)
			)
			(layer "B.SilkS")
		)
		(fp_line
			(start 1.2954 -0.5842)
			(end -1.2954 -0.5842)
			(stroke
				(width 0.1524)
				(type default)
			)
			(layer "B.SilkS")
		)
		(fp_line
			(start -0.8636 0.4572)
			(end 0.8636 0.4572)
			(stroke
				(width 0.1)
				(type default)
			)
			(layer "B.Fab")
		)
		(fp_line
			(start 0.8636 0.4572)
			(end 0.8636 0.4064)
			(stroke
				(width 0.1)
				(type default)
			)
			(layer "B.Fab")
		)
		(fp_line
			(start -1.1938 0.4064)
			(end -0.8636 0.4064)
			(stroke
				(width 0.1)
				(type default)
			)
			(layer "B.Fab")
		)
		(fp_line
			(start -0.8636 0.4064)
			(end -0.8636 0.4572)
			(stroke
				(width 0.1)
				(type default)
			)
			(layer "B.Fab")
		)
		(fp_line
			(start 0.8636 0.4064)
			(end 1.1938 0.4064)
			(stroke
				(width 0.1)
				(type default)
			)
			(layer "B.Fab")
		)
		(fp_line
			(start 1.1938 0.4064)
			(end 1.1938 -0.4064)
			(stroke
				(width 0.1)
				(type default)
			)
			(layer "B.Fab")
		)
		(fp_line
			(start -1.1938 -0.4064)
			(end -1.1938 0.4064)
			(stroke
				(width 0.1)
				(type default)
			)
			(layer "B.Fab")
		)
		(fp_line
			(start -0.8636 -0.4064)
			(end -1.1938 -0.4064)
			(stroke
				(width 0.1)
				(type default)
			)
			(layer "B.Fab")
		)
		(fp_line
			(start 0.8636 -0.4064)
			(end 0.8636 -0.4572)
			(stroke
				(width 0.1)
				(type default)
			)
			(layer "B.Fab")
		)
		(fp_line
			(start 1.1938 -0.4064)
			(end 0.8636 -0.4064)
			(stroke
				(width 0.1)
				(type default)
			)
			(layer "B.Fab")
		)
		(fp_line
			(start -0.8636 -0.4572)
			(end -0.8636 -0.4064)
			(stroke
				(width 0.1)
				(type default)
			)
			(layer "B.Fab")
		)
		(fp_line
			(start 0.8636 -0.4572)
			(end -0.8636 -0.4572)
			(stroke
				(width 0.1)
				(type default)
			)
			(layer "B.Fab")
		)
		(pad "1" smd rect
			(at 0.7366 0 180)
			(size 0.7112 0.8128)
			(layers "B.Cu" "B.Mask" "B.Paste")
			(net "P0V8_SERDES_VDDA_PEX2_C2")
		)
		(pad "2" smd rect
			(at -0.7366 0 180)
			(size 0.7112 0.8128)
			(layers "B.Cu" "B.Mask" "B.Paste")
			(net "GND")
		)
	)
	(footprint ""
		(layer "B.Cu")
		(at 231.466644 -231.225598 90)
		(property "Reference" "R4541"
			(at 0 0 90)
			(layer "B.SilkS")
			(hide yes)
			(effects
				(font
					(size 1.27 1.27)
				)
				(justify mirror)
			)
		)
		(property "Value" ""
			(at 0 0 90)
			(layer "B.Fab")
			(effects
				(font
					(size 1.27 1.27)
				)
				(justify mirror)
			)
		)
		(duplicate_pad_numbers_are_jumpers no)
		(fp_line
			(start 0.7874 -0.4064)
			(end -0.7874 -0.4064)
			(stroke
				(width 0.1524)
				(type default)
			)
			(layer "B.SilkS")
		)
		(fp_line
			(start -0.7874 -0.4064)
			(end -0.7874 0.4064)
			(stroke
				(width 0.1524)
				(type default)
			)
			(layer "B.SilkS")
		)
		(fp_line
			(start 0.7874 0.4064)
			(end 0.7874 -0.4064)
			(stroke
				(width 0.1524)
				(type default)
			)
			(layer "B.SilkS")
		)
		(fp_line
			(start -0.7874 0.4064)
			(end 0.7874 0.4064)
			(stroke
				(width 0.1524)
				(type default)
			)
			(layer "B.SilkS")
		)
		(fp_line
			(start 0.67945 -0.305054)
			(end 0.12065 -0.305054)
			(stroke
				(width 0.1)
				(type default)
			)
			(layer "B.Fab")
		)
		(fp_line
			(start 0.12065 -0.305054)
			(end 0.12065 -0.2794)
			(stroke
				(width 0.1)
				(type default)
			)
			(layer "B.Fab")
		)
		(fp_line
			(start -0.12065 -0.3048)
			(end -0.67945 -0.3048)
			(stroke
				(width 0.1)
				(type default)
			)
			(layer "B.Fab")
		)
		(fp_line
			(start -0.67945 -0.3048)
			(end -0.67945 0.3048)
			(stroke
				(width 0.1)
				(type default)
			)
			(layer "B.Fab")
		)
		(fp_line
			(start 0.12065 -0.2794)
			(end -0.12065 -0.2794)
			(stroke
				(width 0.1)
				(type default)
			)
			(layer "B.Fab")
		)
		(fp_line
			(start -0.12065 -0.2794)
			(end -0.12065 -0.3048)
			(stroke
				(width 0.1)
				(type default)
			)
			(layer "B.Fab")
		)
		(fp_line
			(start 0.12065 0.2794)
			(end 0.12065 0.3048)
			(stroke
				(width 0.1)
				(type default)
			)
			(layer "B.Fab")
		)
		(fp_line
			(start -0.120396 0.2794)
			(end 0.12065 0.2794)
			(stroke
				(width 0.1)
				(type default)
			)
			(layer "B.Fab")
		)
		(fp_line
			(start 0.67945 0.3048)
			(end 0.67945 -0.305054)
			(stroke
				(width 0.1)
				(type default)
			)
			(layer "B.Fab")
		)
		(fp_line
			(start 0.12065 0.3048)
			(end 0.67945 0.3048)
			(stroke
				(width 0.1)
				(type default)
			)
			(layer "B.Fab")
		)
		(fp_line
			(start -0.120396 0.3048)
			(end -0.120396 0.2794)
			(stroke
				(width 0.1)
				(type default)
			)
			(layer "B.Fab")
		)
		(fp_line
			(start -0.67945 0.3048)
			(end -0.120396 0.3048)
			(stroke
				(width 0.1)
				(type default)
			)
			(layer "B.Fab")
		)
		(pad "1" smd circle
			(at 0.40005 0 270)
			(size 0 0)
			(layers "B.Cu" "B.Mask" "B.Paste")
			(net "NIC5_MAIN_PWR_BIC_EN_R")
		)
		(pad "2" smd circle
			(at -0.40005 0 270)
			(size 0 0)
			(layers "B.Cu" "B.Mask" "B.Paste")
			(net "NIC5_MAIN_PWR_BIC_EN")
		)
	)
	(footprint ""
		(layer "B.Cu")
		(at 63.449962 -290.199826 90)
		(property "Reference" "C1237"
			(at 0 0 90)
			(layer "B.SilkS")
			(hide yes)
			(effects
				(font
					(size 1.27 1.27)
				)
				(justify mirror)
			)
		)
		(property "Value" ""
			(at 0 0 90)
			(layer "B.Fab")
			(effects
				(font
					(size 1.27 1.27)
				)
				(justify mirror)
			)
		)
		(duplicate_pad_numbers_are_jumpers no)
		(fp_line
			(start 0.299974 -0.150114)
			(end -0.299974 -0.150114)
			(stroke
				(width 0.1)
				(type default)
			)
			(layer "B.Fab")
		)
		(fp_line
			(start -0.299974 -0.150114)
			(end -0.299974 0.150114)
			(stroke
				(width 0.1)
				(type default)
			)
			(layer "B.Fab")
		)
		(fp_line
			(start 0.299974 0.150114)
			(end 0.299974 -0.150114)
			(stroke
				(width 0.1)
				(type default)
			)
			(layer "B.Fab")
		)
		(fp_line
			(start -0.299974 0.150114)
			(end 0.299974 0.150114)
			(stroke
				(width 0.1)
				(type default)
			)
			(layer "B.Fab")
		)
		(pad "1" smd rect
			(at 0.2667 0 270)
			(size 0.3048 0.381)
			(layers "B.Cu" "B.Mask" "B.Paste")
			(net "P0V8_SERDES_VDDA_PEX0")
		)
		(pad "2" smd rect
			(at -0.2667 0 270)
			(size 0.3048 0.381)
			(layers "B.Cu" "B.Mask" "B.Paste")
			(net "GND")
		)
	)
	(footprint ""
		(layer "B.Cu")
		(at 345.057476 -313.620404 180)
		(property "Reference" "R5792"
			(at 0 0 0)
			(layer "B.SilkS")
			(hide yes)
			(effects
				(font
					(size 1.27 1.27)
				)
				(justify mirror)
			)
		)
		(property "Value" ""
			(at 0 0 0)
			(layer "B.Fab")
			(effects
				(font
					(size 1.27 1.27)
				)
				(justify mirror)
			)
		)
		(duplicate_pad_numbers_are_jumpers no)
		(fp_line
			(start 2.576322 1.1303)
			(end 2.576322 -1.1303)
			(stroke
				(width 0.1524)
				(type default)
			)
			(layer "B.SilkS")
		)
		(fp_line
			(start 2.576322 -1.1303)
			(end -2.576322 -1.1303)
			(stroke
				(width 0.1524)
				(type default)
			)
			(layer "B.SilkS")
		)
		(fp_line
			(start -2.576322 1.1303)
			(end 2.576322 1.1303)
			(stroke
				(width 0.1524)
				(type default)
			)
			(layer "B.SilkS")
		)
		(fp_line
			(start -2.576322 -1.1303)
			(end -2.576322 1.1303)
			(stroke
				(width 0.1524)
				(type default)
			)
			(layer "B.SilkS")
		)
		(fp_line
			(start 1.649984 0.899922)
			(end -1.649984 0.899922)
			(stroke
				(width 0.1)
				(type default)
			)
			(layer "B.Fab")
		)
		(fp_line
			(start 1.649984 -0.899922)
			(end 1.649984 0.899922)
			(stroke
				(width 0.1)
				(type default)
			)
			(layer "B.Fab")
		)
		(fp_line
			(start -1.649984 0.899922)
			(end -1.649984 -0.899922)
			(stroke
				(width 0.1)
				(type default)
			)
			(layer "B.Fab")
		)
		(fp_line
			(start -1.649984 -0.899922)
			(end 1.649984 -0.899922)
			(stroke
				(width 0.1)
				(type default)
			)
			(layer "B.Fab")
		)
		(pad "1A" smd rect
			(at 1.700022 0)
			(size 1.4986 2.0066)
			(layers "B.Cu" "B.Mask" "B.Paste")
			(net "P0V8_PEX2")
		)
		(pad "1B" smd rect
			(at 1.077722 0)
			(size 0.254 0.508)
			(layers "B.Cu" "B.Mask" "B.Paste")
			(net "P0V8_PEX2")
		)
		(pad "2A" smd rect
			(at -1.700022 0)
			(size 1.4986 2.0066)
			(layers "B.Cu" "B.Mask" "B.Paste")
			(net "P0V8_SERDES_VDDA_PEX2")
		)
		(pad "2B" smd rect
			(at -1.077722 0)
			(size 0.254 0.508)
			(layers "B.Cu" "B.Mask" "B.Paste")
			(net "P0V8_SERDES_VDDA_PEX2")
		)
	)
	(footprint ""
		(layer "B.Cu")
		(at 160.549844 -292.099746)
		(property "Reference" "C3174"
			(at 0 0 0)
			(layer "B.SilkS")
			(hide yes)
			(effects
				(font
					(size 1.27 1.27)
				)
				(justify mirror)
			)
		)
		(property "Value" ""
			(at 0 0 0)
			(layer "B.Fab")
			(effects
				(font
					(size 1.27 1.27)
				)
				(justify mirror)
			)
		)
		(duplicate_pad_numbers_are_jumpers no)
		(fp_line
			(start -0.299974 -0.150114)
			(end -0.299974 0.150114)
			(stroke
				(width 0.1)
				(type default)
			)
			(layer "B.Fab")
		)
		(fp_line
			(start -0.299974 0.150114)
			(end 0.299974 0.150114)
			(stroke
				(width 0.1)
				(type default)
			)
			(layer "B.Fab")
		)
		(fp_line
			(start 0.299974 -0.150114)
			(end -0.299974 -0.150114)
			(stroke
				(width 0.1)
				(type default)
			)
			(layer "B.Fab")
		)
		(fp_line
			(start 0.299974 0.150114)
			(end 0.299974 -0.150114)
			(stroke
				(width 0.1)
				(type default)
			)
			(layer "B.Fab")
		)
		(pad "1" smd rect
			(at 0.2667 0 180)
			(size 0.3048 0.381)
			(layers "B.Cu" "B.Mask" "B.Paste")
			(net "P1V8_PEX")
		)
		(pad "2" smd rect
			(at -0.2667 0 180)
			(size 0.3048 0.381)
			(layers "B.Cu" "B.Mask" "B.Paste")
			(net "GND")
		)
	)
)
